(kicad_pcb
	(version 20260206)
	(generator "pcbnew")
	(generator_version "10.0")
	(general
		(thickness 1.6)
		(legacy_teardrops no)
	)
	(paper "A4")
	(title_block
		(title "Bryce Canyon_F.DPB_16315-1-OCP.brd")
		(comment 1 "Bryce Canyon / footprints 1706-1713 of 2223")
	)
	(layers
		(0 "F.Cu" signal "TOP")
		(4 "In1.Cu" signal "L2GND")
		(6 "In2.Cu" signal "L3")
		(8 "In3.Cu" signal "L4GND")
		(10 "In4.Cu" signal "L5")
		(12 "In5.Cu" signal "L6VCC")
		(14 "In6.Cu" signal "L7VCC")
		(16 "In7.Cu" signal "L8")
		(18 "In8.Cu" signal "L9GND")
		(20 "In9.Cu" signal "L10")
		(22 "In10.Cu" signal "L11GND")
		(2 "B.Cu" signal "BOTTOM")
		(9 "F.Adhes" user "F.Adhesive")
		(11 "B.Adhes" user "B.Adhesive")
		(13 "F.Paste" user "Package Geometry/Pastemask Top")
		(15 "B.Paste" user "Package Geometry/Pastemask Bottom")
		(5 "F.SilkS" user "Ref Des/Silkscreen Top")
		(7 "B.SilkS" user "Ref Des/Silkscreen Bottom")
		(1 "F.Mask" user "Board Geometry/Soldermask Top")
		(3 "B.Mask" user "Board Geometry/Soldermask Bottom")
		(17 "Dwgs.User" user "User.Drawings")
		(19 "Cmts.User" user "User.Comments")
		(21 "Eco1.User" user "User.Eco1")
		(23 "Eco2.User" user "User.Eco2")
		(25 "Edge.Cuts" user "Board Geometry/Outline")
		(27 "Margin" user)
		(31 "F.CrtYd" user "Package Geometry/Place Bound Top")
		(29 "B.CrtYd" user "Package Geometry/Place Bound Bottom")
		(35 "F.Fab" user "Ref Des/Assembly Top")
		(33 "B.Fab" user "Ref Des/Assembly Bottom")
	)
	(footprint ""
		(layer "F.Cu")
		(at 118.890796 -304.462942 180)
		(property "Reference" "C86"
			(at 0 0 180)
			(layer "F.SilkS")
			(hide yes)
			(effects
				(font
					(size 1.27 1.27)
				)
			)
		)
		(property "Value" "SC1U25V3KX-GP"
			(at 0 -2.8194 180)
			(unlocked yes)
			(layer "F.Fab")
			(hide yes)
			(effects
				(font
					(size 1.016 1.016)
					(thickness 0.1524)
				)
			)
		)
		(property "Device Type" "C603H36"
			(at 0 -4.3434 180)
			(unlocked yes)
			(layer "F.Fab")
			(hide yes)
			(effects
				(font
					(size 1.016 1.016)
					(thickness 0.1524)
				)
			)
		)
		(duplicate_pad_numbers_are_jumpers no)
		(fp_line
			(start 0.508 0)
			(end -0.508 0)
			(stroke
				(width 0.2032)
				(type default)
			)
			(layer "F.SilkS")
		)
		(fp_rect
			(start -0.5842 1.3335)
			(end 0.5842 -1.3335)
			(stroke
				(width 0)
				(type default)
			)
			(fill no)
			(layer "F.CrtYd")
		)
		(fp_rect
			(start -0.5842 1.3335)
			(end 0.5842 -1.3335)
			(stroke
				(width 0)
				(type default)
			)
			(fill no)
			(layer "F.Fab")
		)
		(pad "1" smd custom
			(at 0 -0.762 180)
			(size 0.2159 0.2159)
			(layers "F.Cu" "F.Mask" "F.Paste")
			(net "P12V_HDD3")
			(options
				(clearance outline)
				(anchor circle)
			)
			(primitives
				(gr_poly
					(pts
						(arc
							(start -0.3302 -0.4318)
							(mid -0.402042 -0.402042)
							(end -0.4318 -0.3302)
						)
						(arc
							(start -0.4318 0.3302)
							(mid -0.402042 0.402042)
							(end -0.3302 0.4318)
						)
						(arc
							(start 0.3302 0.4318)
							(mid 0.402042 0.402042)
							(end 0.4318 0.3302)
						)
						(arc
							(start 0.4318 -0.3302)
							(mid 0.402042 -0.402042)
							(end 0.3302 -0.4318)
						)
					)
					(width 0)
					(fill yes)
				)
			)
		)
		(pad "2" smd custom
			(at 0 0.762 180)
			(size 0.2159 0.2159)
			(layers "F.Cu" "F.Mask" "F.Paste")
			(net "GND")
			(options
				(clearance outline)
				(anchor circle)
			)
			(primitives
				(gr_poly
					(pts
						(arc
							(start -0.3302 -0.4318)
							(mid -0.402042 -0.402042)
							(end -0.4318 -0.3302)
						)
						(arc
							(start -0.4318 0.3302)
							(mid -0.402042 0.402042)
							(end -0.3302 0.4318)
						)
						(arc
							(start 0.3302 0.4318)
							(mid 0.402042 0.402042)
							(end 0.4318 0.3302)
						)
						(arc
							(start 0.4318 -0.3302)
							(mid 0.402042 -0.402042)
							(end 0.3302 -0.4318)
						)
					)
					(width 0)
					(fill yes)
				)
			)
		)
	)
	(footprint ""
		(layer "F.Cu")
		(at 478.30359 -270.265652 90)
		(property "Reference" "C189"
			(at 0 0 90)
			(layer "F.SilkS")
			(hide yes)
			(effects
				(font
					(size 1.27 1.27)
				)
			)
		)
		(property "Value" "SCD01U50V2KX-1GP"
			(at 1.1811 -2.7051 90)
			(unlocked yes)
			(layer "F.Fab")
			(hide yes)
			(effects
				(font
					(size 1.016 1.016)
					(thickness 0.1524)
				)
			)
		)
		(property "Device Type" "C402H22"
			(at 1.1811 -4.2291 90)
			(unlocked yes)
			(layer "F.Fab")
			(hide yes)
			(effects
				(font
					(size 1.016 1.016)
					(thickness 0.1524)
				)
			)
		)
		(duplicate_pad_numbers_are_jumpers no)
		(fp_rect
			(start -0.4318 0.9525)
			(end 0.4318 -0.9525)
			(stroke
				(width 0)
				(type default)
			)
			(fill no)
			(layer "F.CrtYd")
		)
		(fp_rect
			(start -0.4318 0.9525)
			(end 0.4318 -0.9525)
			(stroke
				(width 0)
				(type default)
			)
			(fill no)
			(layer "F.Fab")
		)
		(pad "1" smd custom
			(at 0 -0.4445 90)
			(size 0.1524 0.1524)
			(layers "F.Cu" "F.Mask" "F.Paste")
			(net "HDD_PRSNT_11")
			(options
				(clearance outline)
				(anchor circle)
			)
			(primitives
				(gr_poly
					(pts
						(arc
							(start 0.3048 -0.2032)
							(mid 0.275042 -0.275042)
							(end 0.2032 -0.3048)
						)
						(arc
							(start -0.2032 -0.3048)
							(mid -0.275042 -0.275042)
							(end -0.3048 -0.2032)
						)
						(arc
							(start -0.3048 0.2032)
							(mid -0.275042 0.275042)
							(end -0.2032 0.3048)
						)
						(arc
							(start 0.2032 0.3048)
							(mid 0.275042 0.275042)
							(end 0.3048 0.2032)
						)
					)
					(width 0)
					(fill yes)
				)
			)
		)
		(pad "2" smd custom
			(at 0 0.4445 90)
			(size 0.1524 0.1524)
			(layers "F.Cu" "F.Mask" "F.Paste")
			(net "GND")
			(options
				(clearance outline)
				(anchor circle)
			)
			(primitives
				(gr_poly
					(pts
						(arc
							(start 0.3048 -0.2032)
							(mid 0.275042 -0.275042)
							(end 0.2032 -0.3048)
						)
						(arc
							(start -0.2032 -0.3048)
							(mid -0.275042 -0.275042)
							(end -0.3048 -0.2032)
						)
						(arc
							(start -0.3048 0.2032)
							(mid -0.275042 0.275042)
							(end -0.2032 0.3048)
						)
						(arc
							(start 0.2032 0.3048)
							(mid 0.275042 0.275042)
							(end 0.3048 0.2032)
						)
					)
					(width 0)
					(fill yes)
				)
			)
		)
	)
	(footprint ""
		(layer "F.Cu")
		(at 136.9949 -127.254)
		(property "Reference" "R309"
			(at 0 0 0)
			(layer "F.SilkS")
			(hide yes)
			(effects
				(font
					(size 1.27 1.27)
				)
			)
		)
		(property "Value" "91R3F-1-GP"
			(at -0.0254 -2.5146 0)
			(unlocked yes)
			(layer "F.Fab")
			(hide yes)
			(effects
				(font
					(size 1.016 1.016)
					(thickness 0.1524)
				)
			)
		)
		(property "Device Type" "R603H22"
			(at -0.0254 -4.0386 0)
			(unlocked yes)
			(layer "F.Fab")
			(hide yes)
			(effects
				(font
					(size 1.016 1.016)
					(thickness 0.1524)
				)
			)
		)
		(duplicate_pad_numbers_are_jumpers no)
		(fp_line
			(start -0.4826 0)
			(end -0.2032 0)
			(stroke
				(width 0.2032)
				(type default)
			)
			(layer "F.SilkS")
		)
		(fp_line
			(start 0.2032 0)
			(end 0.4826 0)
			(stroke
				(width 0.2032)
				(type default)
			)
			(layer "F.SilkS")
		)
		(fp_rect
			(start -0.5842 1.3335)
			(end 0.5842 -1.3335)
			(stroke
				(width 0)
				(type default)
			)
			(fill no)
			(layer "F.CrtYd")
		)
		(fp_rect
			(start -0.5842 1.3335)
			(end 0.5842 -1.3335)
			(stroke
				(width 0)
				(type default)
			)
			(fill no)
			(layer "F.Fab")
		)
		(pad "1" smd custom
			(at 0 -0.762)
			(size 0.2159 0.2159)
			(layers "F.Cu" "F.Mask" "F.Paste")
			(net "P5V_A_2")
			(options
				(clearance outline)
				(anchor circle)
			)
			(primitives
				(gr_poly
					(pts
						(arc
							(start -0.3302 -0.4318)
							(mid -0.402042 -0.402042)
							(end -0.4318 -0.3302)
						)
						(arc
							(start -0.4318 0.3302)
							(mid -0.402042 0.402042)
							(end -0.3302 0.4318)
						)
						(arc
							(start 0.3302 0.4318)
							(mid 0.402042 0.402042)
							(end 0.4318 0.3302)
						)
						(arc
							(start 0.4318 -0.3302)
							(mid 0.402042 -0.402042)
							(end 0.3302 -0.4318)
						)
					)
					(width 0)
					(fill yes)
				)
			)
		)
		(pad "2" smd custom
			(at 0 0.762)
			(size 0.2159 0.2159)
			(layers "F.Cu" "F.Mask" "F.Paste")
			(net "DRV_ACT_16")
			(options
				(clearance outline)
				(anchor circle)
			)
			(primitives
				(gr_poly
					(pts
						(arc
							(start -0.3302 -0.4318)
							(mid -0.402042 -0.402042)
							(end -0.4318 -0.3302)
						)
						(arc
							(start -0.4318 0.3302)
							(mid -0.402042 0.402042)
							(end -0.3302 0.4318)
						)
						(arc
							(start 0.3302 0.4318)
							(mid 0.402042 0.402042)
							(end 0.4318 0.3302)
						)
						(arc
							(start 0.4318 -0.3302)
							(mid 0.402042 -0.402042)
							(end 0.3302 -0.4318)
						)
					)
					(width 0)
					(fill yes)
				)
			)
		)
	)
	(footprint ""
		(layer "F.Cu")
		(at 381.5842 -298.704)
		(property "Reference" "TP42"
			(at 0 0 0)
			(layer "F.SilkS")
			(hide yes)
			(effects
				(font
					(size 1.27 1.27)
				)
			)
		)
		(property "Value" "TPAD32-GP"
			(at -0.0508 -1.6764 0)
			(unlocked yes)
			(layer "F.Fab")
			(hide yes)
			(effects
				(font
					(size 1.016 1.016)
					(thickness 0.1524)
				)
			)
		)
		(property "Device Type" "TPAD32"
			(at -0.0508 -3.2004 0)
			(unlocked yes)
			(layer "F.Fab")
			(hide yes)
			(effects
				(font
					(size 1.016 1.016)
					(thickness 0.1524)
				)
			)
		)
		(duplicate_pad_numbers_are_jumpers no)
		(fp_poly
			(pts
				(arc
					(start 0.4064 0)
					(mid -0.4064 0)
					(end 0.4064 0)
				)
			)
			(stroke
				(width 0)
				(type default)
			)
			(fill no)
			(layer "F.CrtYd")
		)
		(fp_poly
			(pts
				(arc
					(start 0.7112 0)
					(mid -0.7112 0)
					(end 0.7112 0)
				)
			)
			(stroke
				(width 0)
				(type default)
			)
			(fill no)
			(layer "F.Fab")
		)
		(pad "1" smd circle
			(at 0 0)
			(size 0.8128 0.8128)
			(layers "F.Cu" "F.Mask" "F.Paste")
			(net "ACT_HDD_8")
		)
	)
	(footprint ""
		(layer "F.Cu")
		(at 33.3248 -207.79994)
		(property "Reference" ""
			(at 0 0 0)
			(layer "F.SilkS")
			(hide yes)
			(effects
				(font
					(size 1.27 1.27)
				)
			)
		)
		(property "Value" "*"
			(at -8.398764 -8.057642 0)
			(unlocked yes)
			(layer "F.Fab")
			(hide yes)
			(effects
				(font
					(size 1.016 1.016)
					(thickness 0.1524)
				)
			)
		)
		(duplicate_pad_numbers_are_jumpers no)
		(fp_poly
			(pts
				(arc
					(start 7.3152 0)
					(mid 0 7.3152)
					(end -7.3152 0)
				)
				(arc
					(start -7.3152 -5.9944)
					(mid 0 -13.3096)
					(end 7.3152 -5.9944)
				)
			)
			(stroke
				(width 0)
				(type default)
			)
			(fill no)
			(layer "B.CrtYd")
		)
		(fp_poly
			(pts
				(arc
					(start 7.3152 0)
					(mid 0 7.3152)
					(end -7.3152 0)
				)
				(arc
					(start -7.3152 -5.9944)
					(mid 0 -13.3096)
					(end 7.3152 -5.9944)
				)
			)
			(stroke
				(width 0)
				(type default)
			)
			(fill no)
			(layer "F.CrtYd")
		)
		(fp_poly
			(pts
				(arc
					(start 7.3152 0)
					(mid 0 7.3152)
					(end -7.3152 0)
				)
				(arc
					(start -7.3152 -5.9944)
					(mid 0 -13.3096)
					(end 7.3152 -5.9944)
				)
			)
			(stroke
				(width 0)
				(type default)
			)
			(fill no)
			(layer "B.Fab")
		)
		(fp_poly
			(pts
				(arc
					(start 7.3152 0)
					(mid 0 7.3152)
					(end -7.3152 0)
				)
				(arc
					(start -7.3152 -5.9944)
					(mid 0 -13.3096)
					(end 7.3152 -5.9944)
				)
			)
			(stroke
				(width 0)
				(type default)
			)
			(fill no)
			(layer "F.Fab")
		)
		(pad "1" thru_hole oval
			(at 0 0)
			(size 14.0208 20.0152)
			(drill 0.0254
				(offset 0 -2.9972)
			)
			(layers "*.Cu" "*.Mask")
			(remove_unused_layers no)
			(net "Net_103")
			(clearance -1.002284)
			(thermal_gap 0.1524)
			(padstack
				(mode front_inner_back)
				(layer "Inner"
					(shape custom)
					(size 2.928012 2.928012)
					(options
						(anchor circle)
					)
					(primitives
						(gr_poly
							(pts
								(arc
									(start 4.571746 -2.084324)
									(mid 0.000333 7.430372)
									(end -4.571492 -2.084324)
								)
								(arc
									(start -4.571492 -2.084324)
									(mid -3.570296 -3.611977)
									(end -2.875026 -5.30098)
								)
								(arc
									(start -2.875026 -5.30098)
									(mid 0.000217 -7.43089)
									(end 2.87528 -5.30098)
								)
								(arc
									(start 2.87528 -5.30098)
									(mid 3.570511 -3.611956)
									(end 4.571746 -2.084324)
								)
							)
							(width 0)
							(fill yes)
						)
					)
					(clearance 0.1524)
				)
				(layer "B.Cu"
					(shape oval)
					(size 14.0208 20.0152)
					(offset 0 -2.9972)
					(clearance -1.002284)
				)
			)
		)
		(zone
			(layers "F.Cu" "B.Cu" "In1.Cu" "In2.Cu" "In3.Cu" "In4.Cu" "In5.Cu" "In6.Cu"
				"In7.Cu" "In8.Cu" "In9.Cu" "In10.Cu"
			)
			(hatch none 0.5)
			(connect_pads
				(clearance 0)
			)
			(min_thickness 0.25)
			(keepout
				(tracks not_allowed)
				(vias allowed)
				(pads allowed)
				(copperpour not_allowed)
				(footprints allowed)
			)
			(placement
				(enabled no)
				(sheetname "")
			)
			(fill
				(thermal_gap 0.5)
				(thermal_bridge_width 0.5)
				(island_removal_mode 0)
			)
			(polygon
				(pts
					(arc
						(start 26.3144 -213.79434)
						(mid 33.3248 -220.80474)
						(end 40.3352 -213.79434)
					)
					(arc
						(start 40.3352 -207.79994)
						(mid 33.3248 -200.78954)
						(end 26.3144 -207.79994)
					)
				)
			)
		)
	)
	(footprint ""
		(layer "F.Cu")
		(at 468.903304 -179.683918 -90)
		(property "Reference" "C344"
			(at 0 0 270)
			(layer "F.SilkS")
			(hide yes)
			(effects
				(font
					(size 1.27 1.27)
				)
			)
		)
		(property "Value" "SC4D7U25V5KX-1-GP"
			(at -0.0762 -6.1214 270)
			(unlocked yes)
			(layer "F.Fab")
			(hide yes)
			(effects
				(font
					(size 1.016 1.016)
					(thickness 0.1524)
				)
			)
		)
		(property "Device Type" "C805H58"
			(at -0.0762 -8.1534 270)
			(unlocked yes)
			(layer "F.Fab")
			(hide yes)
			(effects
				(font
					(size 1.016 1.016)
					(thickness 0.1524)
				)
			)
		)
		(duplicate_pad_numbers_are_jumpers no)
		(fp_line
			(start 0.635 0)
			(end -0.635 0)
			(stroke
				(width 0.508)
				(type default)
			)
			(layer "F.SilkS")
		)
		(fp_rect
			(start -0.9652 1.778)
			(end 0.9652 -1.778)
			(stroke
				(width 0)
				(type default)
			)
			(fill no)
			(layer "F.CrtYd")
		)
		(fp_poly
			(pts
				(xy -0.9652 -1.778) (xy 0.9652 -1.778) (xy 0.9652 1.778) (xy -0.9652 1.778)
			)
			(stroke
				(width 0)
				(type default)
			)
			(fill no)
			(layer "F.Fab")
		)
		(pad "1" smd rect
			(at 0 -0.9652 270)
			(size 1.397 1.143)
			(layers "F.Cu" "F.Mask" "F.Paste")
			(net "P12V_HDD23")
		)
		(pad "2" smd rect
			(at 0 0.9652 270)
			(size 1.397 1.143)
			(layers "F.Cu" "F.Mask" "F.Paste")
			(net "GND")
		)
	)
	(footprint ""
		(layer "F.Cu")
		(at 180.7464 -159.871918 -90)
		(property "Reference" "R531"
			(at 0 0 270)
			(layer "F.SilkS")
			(hide yes)
			(effects
				(font
					(size 1.27 1.27)
				)
			)
		)
		(property "Value" "0R2J-2-GP"
			(at 0.064008 -3.993896 270)
			(unlocked yes)
			(layer "F.Fab")
			(hide yes)
			(effects
				(font
					(size 1.016 1.016)
					(thickness 0.1524)
				)
			)
		)
		(property "Device Type" "R402H16"
			(at 0.064008 -5.517896 270)
			(unlocked yes)
			(layer "F.Fab")
			(hide yes)
			(effects
				(font
					(size 1.016 1.016)
					(thickness 0.1524)
				)
			)
		)
		(duplicate_pad_numbers_are_jumpers no)
		(fp_line
			(start -0.508 -0.9398)
			(end -0.508 0.9398)
			(stroke
				(width 0.1524)
				(type default)
			)
			(layer "F.SilkS")
		)
		(fp_line
			(start 0.508 -0.9398)
			(end -0.508 -0.9398)
			(stroke
				(width 0.1524)
				(type default)
			)
			(layer "F.SilkS")
		)
		(fp_rect
			(start -0.508 0.9398)
			(end 0.508 -0.9398)
			(stroke
				(width 0)
				(type default)
			)
			(fill no)
			(layer "F.CrtYd")
		)
		(fp_rect
			(start -0.508 0.9398)
			(end 0.508 -0.9398)
			(stroke
				(width 0)
				(type default)
			)
			(fill no)
			(layer "F.Fab")
		)
		(pad "1" smd custom
			(at 0 -0.4445 270)
			(size 0.1397 0.1397)
			(layers "F.Cu" "F.Mask" "F.Paste")
			(net "DRIVE_A_17_PWR")
			(options
				(clearance outline)
				(anchor circle)
			)
			(primitives
				(gr_poly
					(pts
						(arc
							(start -0.1778 -0.2794)
							(mid -0.249642 -0.249642)
							(end -0.2794 -0.1778)
						)
						(arc
							(start -0.2794 0.1778)
							(mid -0.249642 0.249642)
							(end -0.1778 0.2794)
						)
						(arc
							(start 0.1778 0.2794)
							(mid 0.249642 0.249642)
							(end 0.2794 0.1778)
						)
						(arc
							(start 0.2794 -0.1778)
							(mid 0.249642 -0.249642)
							(end 0.1778 -0.2794)
						)
					)
					(width 0)
					(fill yes)
				)
			)
		)
		(pad "2" smd custom
			(at 0 0.4445 270)
			(size 0.1397 0.1397)
			(layers "F.Cu" "F.Mask" "F.Paste")
			(net "SW_PWR_R_HDD17")
			(options
				(clearance outline)
				(anchor circle)
			)
			(primitives
				(gr_poly
					(pts
						(arc
							(start -0.1778 -0.2794)
							(mid -0.249642 -0.249642)
							(end -0.2794 -0.1778)
						)
						(arc
							(start -0.2794 0.1778)
							(mid -0.249642 0.249642)
							(end -0.1778 0.2794)
						)
						(arc
							(start 0.1778 0.2794)
							(mid 0.249642 0.249642)
							(end 0.2794 0.1778)
						)
						(arc
							(start 0.2794 -0.1778)
							(mid 0.249642 -0.249642)
							(end 0.1778 -0.2794)
						)
					)
					(width 0)
					(fill yes)
				)
			)
		)
	)
	(footprint ""
		(layer "F.Cu")
		(at 222.928942 -219.304362)
		(property "Reference" "R415"
			(at 0 0 0)
			(layer "F.SilkS")
			(hide yes)
			(effects
				(font
					(size 1.27 1.27)
				)
			)
		)
		(property "Value" "1KR2F-3-GP"
			(at 0.064008 -3.993896 0)
			(unlocked yes)
			(layer "F.Fab")
			(hide yes)
			(effects
				(font
					(size 1.016 1.016)
					(thickness 0.1524)
				)
			)
		)
		(property "Device Type" "R402H16"
			(at 0.064008 -5.517896 0)
			(unlocked yes)
			(layer "F.Fab")
			(hide yes)
			(effects
				(font
					(size 1.016 1.016)
					(thickness 0.1524)
				)
			)
		)
		(duplicate_pad_numbers_are_jumpers no)
		(fp_line
			(start -0.508 -0.9398)
			(end -0.508 0.9398)
			(stroke
				(width 0.1524)
				(type default)
			)
			(layer "F.SilkS")
		)
		(fp_line
			(start 0.508 -0.9398)
			(end -0.508 -0.9398)
			(stroke
				(width 0.1524)
				(type default)
			)
			(layer "F.SilkS")
		)
		(fp_rect
			(start -0.508 0.9398)
			(end 0.508 -0.9398)
			(stroke
				(width 0)
				(type default)
			)
			(fill no)
			(layer "F.CrtYd")
		)
		(fp_rect
			(start -0.508 0.9398)
			(end 0.508 -0.9398)
			(stroke
				(width 0)
				(type default)
			)
			(fill no)
			(layer "F.Fab")
		)
		(pad "1" smd custom
			(at 0 -0.4445)
			(size 0.1397 0.1397)
			(layers "F.Cu" "F.Mask" "F.Paste")
			(net "P3V3_STBY_A")
			(options
				(clearance outline)
				(anchor circle)
			)
			(primitives
				(gr_poly
					(pts
						(arc
							(start -0.1778 -0.2794)
							(mid -0.249642 -0.249642)
							(end -0.2794 -0.1778)
						)
						(arc
							(start -0.2794 0.1778)
							(mid -0.249642 0.249642)
							(end -0.1778 0.2794)
						)
						(arc
							(start 0.1778 0.2794)
							(mid 0.249642 0.249642)
							(end 0.2794 0.1778)
						)
						(arc
							(start 0.2794 -0.1778)
							(mid 0.249642 -0.249642)
							(end 0.1778 -0.2794)
						)
					)
					(width 0)
					(fill yes)
				)
			)
		)
		(pad "2" smd custom
			(at 0 0.4445)
			(size 0.1397 0.1397)
			(layers "F.Cu" "F.Mask" "F.Paste")
			(net "I2C_SCC_A_SDA_BUF")
			(options
				(clearance outline)
				(anchor circle)
			)
			(primitives
				(gr_poly
					(pts
						(arc
							(start -0.1778 -0.2794)
							(mid -0.249642 -0.249642)
							(end -0.2794 -0.1778)
						)
						(arc
							(start -0.2794 0.1778)
							(mid -0.249642 0.249642)
							(end -0.1778 0.2794)
						)
						(arc
							(start 0.1778 0.2794)
							(mid 0.249642 0.249642)
							(end 0.2794 0.1778)
						)
						(arc
							(start 0.2794 -0.1778)
							(mid 0.249642 -0.249642)
							(end 0.1778 -0.2794)
						)
					)
					(width 0)
					(fill yes)
				)
			)
		)
	)
)
